FILE_TYPE = MULTI_PHYS_TABLE;

PART 'TPS71715DCKR'

{========================================================================================}
:VALUE          | PART_TYPE | MATERIAL | PART_NUMBER    = STANDARD    | LIFECYCLE     | PART_NUMBER   | JEDEC_TYPE | DESCRIPTION                | MANUFTR | MANUF_PN       | RD_CMPLS_LVL | CMPLS_LVL | FROM_PJ       | CLASS | DIP_SMD | DATA                   | EE_CHECK_LIST | FP_ECN | PSL | CREATOR | STATUS | MSD | ESD_CDM | ESD_HBM | ESD_MM | PIN_LENGTH_SHORT_PIN | PIN_LENGTH_LONG_PIN | CREATEDAY  ;
{========================================================================================}
 'TPS71715DCKR' | 'SMLF'    | 'IC'     | 'AL071715001'(!) = ''               | ''               | 'AL071715001' |'SC70-5XB'| 'IC(5P)TPS71715DCKR(SC70)' | 'TIC'   | 'TPS71715DCKR' | 'EP(V1)'     | 'SEA'     | 'F0TG-KUO-JU' | 'IC'  | ''      | 'TIC_TPS71715DCKR.pdf' | ''            | ''     | ''  | ''      | ''     | ''  | ''      | ''      | ''     | '0 MILS'             | '0 MILS'            | '20220517'
 'TPS71715DCKR' | 'SMLF'    | 'EMPTY'  | 'AL071715001'(!) = ''               | ''               | 'AL071715001' |'SC70-5XB'| 'IC(5P)TPS71715DCKR(SC70)' | 'TIC'   | 'TPS71715DCKR' | 'EP(V1)'     | 'SEA'     | 'F0TG-KUO-JU' | 'IC'  | ''      | 'TIC_TPS71715DCKR.pdf' | ''            | ''     | ''  | ''      | ''     | ''  | ''      | ''      | ''     | '0 MILS'             | '0 MILS'            | '20220517'

END_PART

END.

